# BASEBOARD_FAB2 (Tioga Pass) — schematic netlist excerpt (pin names and nets, part order shuffled) for the footprints in the layout excerpt that follows; sources: Cadence DE-HDL packaged netlist, KiCad conversion of Wiwynn_Tioga_Pass_MB.brd

C1R26  CAP_A  0.1UF 16V 10% X7R  pkg 0402V  page 139 : A = P1V5_LAN ; B = GND
C1T4  CAP  10UF 6.3V 20% X6S  pkg 0603  page 139 : A = P0V9_LAN ; B = GND
C8P20  CAP  47UF 4V 20% X6S  pkg 0805  page 76 : A = PVCCIN_CPU1 ; B = GND

(kicad_pcb
	(version 20260206)
	(generator "pcbnew")
	(generator_version "10.0")
	(general
		(thickness 1.6)
		(legacy_teardrops no)
	)
	(paper "A4")
	(title_block
		(title "Wiwynn_Tioga_Pass_MB.brd")
		(comment 1 "Tioga Pass / footprints 3724-3726 of 4770")
	)
	(layers
		(0 "F.Cu" signal "TOP")
		(4 "In1.Cu" signal "L2GND")
		(6 "In2.Cu" signal "L3")
		(8 "In3.Cu" signal "L4GND")
		(10 "In4.Cu" signal "L5")
		(12 "In5.Cu" signal "L6GND")
		(14 "In6.Cu" signal "L7VCC")
		(16 "In7.Cu" signal "L8VCC")
		(18 "In8.Cu" signal "L9GND")
		(20 "In9.Cu" signal "L10")
		(22 "In10.Cu" signal "L11GND")
		(24 "In11.Cu" signal "L12")
		(26 "In12.Cu" signal "L13GND")
		(2 "B.Cu" signal "BOTTOM")
		(9 "F.Adhes" user "F.Adhesive")
		(11 "B.Adhes" user "B.Adhesive")
		(13 "F.Paste" user "Package Geometry/Pastemask Top")
		(15 "B.Paste" user "Package Geometry/Pastemask Bottom")
		(5 "F.SilkS" user "Ref Des/Silkscreen Top")
		(7 "B.SilkS" user "Ref Des/Silkscreen Bottom")
		(1 "F.Mask" user "Board Geometry/Soldermask Top")
		(3 "B.Mask" user "Board Geometry/Soldermask Bottom")
		(17 "Dwgs.User" user "User.Drawings")
		(19 "Cmts.User" user "User.Comments")
		(21 "Eco1.User" user "User.Eco1")
		(23 "Eco2.User" user "User.Eco2")
		(25 "Edge.Cuts" user "Board Geometry/Outline")
		(27 "Margin" user)
		(31 "F.CrtYd" user "Package Geometry/Place Bound Top")
		(29 "B.CrtYd" user "Package Geometry/Place Bound Bottom")
		(35 "F.Fab" user "Ref Des/Assembly Top")
		(33 "B.Fab" user "Ref Des/Assembly Bottom")
	)
	(footprint ""
		(layer "B.Cu")
		(at 95.377254 -77.82814)
		(property "Reference" "C8P20"
			(at 0 0 0)
			(layer "B.SilkS")
			(hide yes)
			(effects
				(font
					(size 1.27 1.27)
				)
				(justify mirror)
			)
		)
		(property "Value" ""
			(at 0 0 0)
			(layer "B.Fab")
			(effects
				(font
					(size 1.27 1.27)
				)
				(justify mirror)
			)
		)
		(duplicate_pad_numbers_are_jumpers no)
		(fp_poly
			(pts
				(xy 0.7239 -0.2159) (xy -0.7239 -0.2159) (xy -0.7239 1.9939) (xy 0.7239 1.9939)
			)
			(stroke
				(width 0)
				(type default)
			)
			(fill no)
			(layer "B.CrtYd")
		)
		(fp_line
			(start -0.7239 -0.2159)
			(end 0.7239 -0.2159)
			(stroke
				(width 0.1)
				(type default)
			)
			(layer "B.Fab")
		)
		(fp_line
			(start -0.7239 1.9939)
			(end -0.7239 -0.2159)
			(stroke
				(width 0.1)
				(type default)
			)
			(layer "B.Fab")
		)
		(fp_line
			(start 0.7239 -0.2159)
			(end 0.7239 1.9939)
			(stroke
				(width 0.1)
				(type default)
			)
			(layer "B.Fab")
		)
		(fp_line
			(start 0.7239 1.9939)
			(end -0.7239 1.9939)
			(stroke
				(width 0.1)
				(type default)
			)
			(layer "B.Fab")
		)
		(pad "1" smd rect
			(at 0 0 180)
			(size 1.27 1.016)
			(layers "B.Cu" "B.Mask" "B.Paste")
			(net "PVCCIN_CPU1")
		)
		(pad "2" smd rect
			(at 0 1.778 180)
			(size 1.27 1.016)
			(layers "B.Cu" "B.Mask" "B.Paste")
			(net "GND")
		)
		(zone
			(layer "B.Cu")
			(hatch none 0.5)
			(connect_pads
				(clearance 0)
			)
			(min_thickness 0.25)
			(keepout
				(tracks not_allowed)
				(vias allowed)
				(pads allowed)
				(copperpour not_allowed)
				(footprints allowed)
			)
			(placement
				(enabled no)
				(sheetname "")
			)
			(fill
				(thermal_gap 0.5)
				(thermal_bridge_width 0.5)
				(island_removal_mode 0)
			)
			(polygon
				(pts
					(xy 96.012254 -77.32014) (xy 94.742254 -77.32014) (xy 94.742254 -76.55814) (xy 96.012254 -76.55814)
				)
			)
		)
	)
	(footprint ""
		(layer "B.Cu")
		(at 479.8695 -40.4114 90)
		(property "Reference" "C1R26"
			(at 0 0 90)
			(layer "B.SilkS")
			(hide yes)
			(effects
				(font
					(size 1.27 1.27)
				)
				(justify mirror)
			)
		)
		(property "Value" ""
			(at 0 0 90)
			(layer "B.Fab")
			(effects
				(font
					(size 1.27 1.27)
				)
				(justify mirror)
			)
		)
		(duplicate_pad_numbers_are_jumpers no)
		(fp_poly
			(pts
				(xy -0.3048 -0.1016) (xy -0.3048 0.9906) (xy 0.3048 0.9906) (xy 0.3048 -0.1016)
			)
			(stroke
				(width 0)
				(type default)
			)
			(fill no)
			(layer "B.CrtYd")
		)
		(fp_line
			(start 0.3048 -0.1016)
			(end 0.3048 0.9906)
			(stroke
				(width 0.1)
				(type default)
			)
			(layer "B.Fab")
		)
		(fp_line
			(start -0.3048 -0.1016)
			(end 0.3048 -0.1016)
			(stroke
				(width 0.1)
				(type default)
			)
			(layer "B.Fab")
		)
		(fp_line
			(start 0.3048 0.9906)
			(end -0.3048 0.9906)
			(stroke
				(width 0.1)
				(type default)
			)
			(layer "B.Fab")
		)
		(fp_line
			(start -0.3048 0.9906)
			(end -0.3048 -0.1016)
			(stroke
				(width 0.1)
				(type default)
			)
			(layer "B.Fab")
		)
		(pad "1" smd rect
			(at 0 0 270)
			(size 0.508 0.508)
			(layers "B.Cu" "B.Mask" "B.Paste")
			(net "P1V5_LAN")
		)
		(pad "2" smd rect
			(at 0 0.889 270)
			(size 0.508 0.508)
			(layers "B.Cu" "B.Mask" "B.Paste")
			(net "GND")
		)
		(zone
			(layer "B.Cu")
			(hatch none 0.5)
			(connect_pads
				(clearance 0)
			)
			(min_thickness 0.25)
			(keepout
				(tracks allowed)
				(vias not_allowed)
				(pads allowed)
				(copperpour not_allowed)
				(footprints allowed)
			)
			(placement
				(enabled no)
				(sheetname "")
			)
			(fill
				(thermal_gap 0.5)
				(thermal_bridge_width 0.5)
				(island_removal_mode 0)
			)
			(polygon
				(pts
					(xy 480.1235 -40.6654) (xy 480.1235 -40.1574) (xy 480.5045 -40.1574) (xy 480.5045 -40.6654)
				)
			)
		)
		(zone
			(layer "B.Cu")
			(hatch none 0.5)
			(connect_pads
				(clearance 0)
			)
			(min_thickness 0.25)
			(keepout
				(tracks not_allowed)
				(vias allowed)
				(pads allowed)
				(copperpour not_allowed)
				(footprints allowed)
			)
			(placement
				(enabled no)
				(sheetname "")
			)
			(fill
				(thermal_gap 0.5)
				(thermal_bridge_width 0.5)
				(island_removal_mode 0)
			)
			(polygon
				(pts
					(xy 480.5045 -40.6654) (xy 480.5045 -40.1574) (xy 480.1235 -40.1574) (xy 480.1235 -40.6654)
				)
			)
		)
	)
	(footprint ""
		(layer "B.Cu")
		(at 485.6734 -39.7256 180)
		(property "Reference" "C1T4"
			(at 0 0 0)
			(layer "B.SilkS")
			(hide yes)
			(effects
				(font
					(size 1.27 1.27)
				)
				(justify mirror)
			)
		)
		(property "Value" ""
			(at 0 0 0)
			(layer "B.Fab")
			(effects
				(font
					(size 1.27 1.27)
				)
				(justify mirror)
			)
		)
		(duplicate_pad_numbers_are_jumpers no)
		(fp_poly
			(pts
				(xy 0.4953 -0.2032) (xy -0.4953 -0.2032) (xy -0.4953 1.6002) (xy 0.4953 1.6002)
			)
			(stroke
				(width 0)
				(type default)
			)
			(fill no)
			(layer "B.CrtYd")
		)
		(fp_line
			(start 0.4953 1.6002)
			(end 0.4953 -0.2032)
			(stroke
				(width 0.1)
				(type default)
			)
			(layer "B.Fab")
		)
		(fp_line
			(start 0.4953 -0.2032)
			(end -0.4953 -0.2032)
			(stroke
				(width 0.1)
				(type default)
			)
			(layer "B.Fab")
		)
		(fp_line
			(start -0.4953 1.6002)
			(end 0.4953 1.6002)
			(stroke
				(width 0.1)
				(type default)
			)
			(layer "B.Fab")
		)
		(fp_line
			(start -0.4953 -0.2032)
			(end -0.4953 1.6002)
			(stroke
				(width 0.1)
				(type default)
			)
			(layer "B.Fab")
		)
		(pad "1" smd rect
			(at 0 0)
			(size 0.762 0.889)
			(layers "B.Cu" "B.Mask" "B.Paste")
			(net "P0V9_LAN")
		)
		(pad "2" smd rect
			(at 0 1.397)
			(size 0.762 0.889)
			(layers "B.Cu" "B.Mask" "B.Paste")
			(net "GND")
		)
		(zone
			(layer "B.Cu")
			(hatch none 0.5)
			(connect_pads
				(clearance 0)
			)
			(min_thickness 0.25)
			(keepout
				(tracks not_allowed)
				(vias allowed)
				(pads allowed)
				(copperpour not_allowed)
				(footprints allowed)
			)
			(placement
				(enabled no)
				(sheetname "")
			)
			(fill
				(thermal_gap 0.5)
				(thermal_bridge_width 0.5)
				(island_removal_mode 0)
			)
			(polygon
				(pts
					(xy 485.2924 -40.1701) (xy 486.0544 -40.1701) (xy 486.0544 -40.6781) (xy 485.2924 -40.6781)
				)
			)
		)
	)
)
